# BASEBOARD_FAB2 (Tioga Pass) — schematic parts with pin connectivity, parts 4665–4665 of 4751; source: Cadence DE-HDL packaged netlist (pstxprt.dat, pstxnet.dat, pstchip.dat)

U5D1  SKX_EXT_B  IC  pkg BGA1  page 21  (pins 2374-2712 of 3647)
  DL32  DDR5_DQS_DN(5)  BI  = M_F_DQS_DN<5>
  DL34  VSS(163)  GROUND  = GND
  DL36  VSS(162)  GROUND  = GND
  DL38  RSVD(35)  BI  = TP_CPU0_RSVD_35
  DL40  VSS(161)  GROUND  = GND
  DL42  DDR4_DQ(36)  BI  = M_E_DQ<36>
  DL44  SVIDALERT_N(1)  IN  = SVID_ALERT1_CPU0_N
  DL46  VCCD345(30)  POWER  = PVDDQ_DEF
  DL48  VCCD345(29)  POWER  = PVDDQ_DEF
  DL50  VCCD345(28)  POWER  = PVDDQ_DEF
  DL52  VCCD345(27)  POWER  = PVDDQ_DEF
  DL54  VCCD345(26)  POWER  = PVDDQ_DEF
  DL56  VCCD345(25)  POWER  = PVDDQ_DEF
  DL58  VCCD345(24)  POWER  = PVDDQ_DEF
  DL60  VCCD345(23)  POWER  = PVDDQ_DEF
  DL62  VCCD345(22)  POWER  = PVDDQ_DEF
  DL64  DDR4_CKE(2)  OUT  = M_E_CKE<2>
  DL66  RSVD(34)  BI  = TP_CPU0_RSVD_34
  DL68  VSS(160)  GROUND  = GND
  DL70  VSS(159)  GROUND  = GND
  DL72  DDR5_DQS_DN(2)  BI  = M_F_DQS_DN<2>
  DL74  VSS(158)  GROUND  = GND
  DL76  VSS(157)  GROUND  = GND
  DL78  VSS(156)  GROUND  = GND
  DL80  VSS(155)  GROUND  = GND
  DL82  DDR3_DQS_DN(2)  BI  = M_D_DQS_DN<2>
  DL84  DDR3_DQS_DP(10)  BI  = M_D_DQS_DP<10>
  DM3  PE1_TX_DN(6)  OUT  = P3E_CPU0_PE1_SS_TXN<6>
  DM5  PE3_TX_DP(9)  OUT  = P3E_CPU0_PE3_OCP_TXP<9>
  DM7  PE3_TX_DN(8)  OUT  = P3E_CPU0_PE3_OCP_TXN<8>
  DM9  PE1_RX_DN(7)  IN  = P3E_CPU0_PE1_SS_RXN<7>
  DM11  PE1_RX_DN(8)  IN  = P3E_CPU0_PE1_PCH_RXN<8>
  DM13  PE3_RX_DP(6)  IN  = P3E_CPU0_PE3_OCP_RXP<6>
  DM15  VSS(154)  GROUND  = GND
  DM17  VCCIO(61)  POWER  = PVCCIO_CPU0
  DM19  VSS(1043)  GROUND  = GND
  DM21  UPI2_TX_DN(1)  OUT  = TP_CPU0_UPI2_RSVD_CC10
  DM23  DDR3_DQS_DN(16)  BI  = M_D_DQS_DN<16>
  DM25  VSS(152)  GROUND  = GND
  DM27  VSS(151)  GROUND  = GND
  DM29  DDR3_DQS_DN(15)  BI  = M_D_DQS_DN<15>
  DM31  VSS(150)  GROUND  = GND
  DM33  VSS(149)  GROUND  = GND
  DM35  DDR3_DQS_DP(14)  BI  = M_D_DQS_DP<14>
  DM37  VSS(148)  GROUND  = GND
  DM39  VSS(147)  GROUND  = GND
  DM41  DDR4_DQS_DP(13)  BI  = M_E_DQS_DP<13>
  DM45  DDR5_CS_N(6)  OUT  = M_F_CS_N<6>
  DM47  DDR4_ODT(3)  OUT  = M_E_ODT<3>
  DM49  DDR4_CS_N(5)  OUT  = M_E_CS_N<5>
  DM51  DDR4_MA(14)  OUT  = M_E_MA<14>
  DM53  DDR4_BA(0)  OUT  = M_E_BA<0>
  DM55  DDR4_CLK_DN(0)  OUT  = M_E_CLK_DN<0>
  DM57  DDR4_CLK_DN(2)  OUT  = M_E_CLK_DN<2>
  DM59  DDR4_MA(6)  OUT  = M_E_MA<6>
  DM61  DDR4_BG(1)  OUT  = M_E_BG<1>
  DM63  DDR4_CKE(0)  OUT  = M_E_CKE<0>
  DM65  VSS(146)  GROUND  = GND
  DM67  RSVD(33)  BI  = TP_CPU0_RSVD_33
  DM69  DDR5_DQ(18)  BI  = M_F_DQ<18>
  DM71  DDR5_DQ(23)  BI  = M_F_DQ<23>
  DM73  VSS(145)  GROUND  = GND
  DM75  DDR3_DQS_DP(12)  BI  = M_D_DQS_DP<12>
  DM77  VSS(144)  GROUND  = GND
  DM79  DDR3_DQ(16)  BI  = M_D_DQ<16>
  DM81  DDR3_DQS_DP(2)  BI  = M_D_DQS_DP<2>
  DM83  VSS(143)  GROUND  = GND
  DM85  DDR3_DQS_DN(10)  BI  = M_D_DQS_DN<10>
  DN2  VSS(142)  GROUND  = GND
  DN4  PE1_TX_DN(7)  OUT  = P3E_CPU0_PE1_SS_TXN<7>
  DN6  PE3_TX_DP(8)  OUT  = P3E_CPU0_PE3_OCP_TXP<8>
  DN8  VCCIO(62)  POWER  = PVCCIO_CPU0
  DN10  PE1_RX_DP(9)  IN  = P3E_CPU0_PE1_PCH_RXP<9>
  DN12  VSS(140)  GROUND  = GND
  DN14  PE3_RX_DN(6)  IN  = P3E_CPU0_PE3_OCP_RXN<6>
  DN16  PE3_RX_DP(4)  IN  = P3E_CPU0_PE3_OCP_RXP<4>
  DN18  VSS(1202)  GROUND  = GND
  DN20  UPI2_TX_DP(1)  OUT  = TP_CPU0_UPI2_RSVD_CB11
  DN22  VSS(139)  GROUND  = GND
  DN24  DDR3_DQ(56)  BI  = M_D_DQ<56>
  DN26  VSS(138)  GROUND  = GND
  DN28  DDR3_DQ(54)  BI  = M_D_DQ<54>
  DN30  DDR3_DQ(48)  BI  = M_D_DQ<48>
  DN32  VSS(137)  GROUND  = GND
  DN34  DDR3_DQ(46)  BI  = M_D_DQ<46>
  DN36  DDR3_DQ(40)  BI  = M_D_DQ<40>
  DN38  VSS(136)  GROUND  = GND
  DN40  DDR4_DQ(38)  BI  = M_E_DQ<38>
  DN42  DDR4_DQ(37)  BI  = M_E_DQ<37>
  DN44  VSS(1106)  GROUND  = GND
  DN46  DDR4_CS_N(7)  OUT  = M_E_CS_N<7>
  DN48  DDR4_ODT(1)  OUT  = M_E_ODT<1>
  DN50  DDR4_CS_N(1)  OUT  = M_E_CS_N<1>
  DN52  DDR4_MA(16)  OUT  = M_E_MA<16>
  DN54  DDR4_CLK_DP(0)  OUT  = M_E_CLK_DP<0>
  DN56  DDR4_CLK_DP(2)  OUT  = M_E_CLK_DP<2>
  DN58  DDR4_MA(5)  OUT  = M_E_MA<5>
  DN60  DDR4_MA(12)  OUT  = M_E_MA<12>
  DN62  RSVD(32)  BI  = TP_CPU0_RSVD_32
  DN64  DDR4_CKE(1)  OUT  = M_E_CKE<1>
  DN66  RSVD(31)  BI  = TP_CPU0_RSVD_31
  DN68  VSS(135)  GROUND  = GND
  DN70  DDR5_DQ(19)  BI  = M_F_DQ<19>
  DN72  VSS(134)  GROUND  = GND
  DN74  DDR3_DQ(30)  BI  = M_D_DQ<30>
  DN76  DDR3_DQ(24)  BI  = M_D_DQ<24>
  DN78  VSS(133)  GROUND  = GND
  DN80  DDR3_DQS_DN(11)  BI  = M_D_DQS_DN<11>
  DN82  DDR3_DQ(23)  BI  = M_D_DQ<23>
  DN84  DDR3_DQS_DN(1)  BI  = M_D_DQS_DN<1>
  DP3  PE1_TX_DP(7)  OUT  = P3E_CPU0_PE1_SS_TXP<7>
  DP5  PE3_TX_DN(9)  OUT  = P3E_CPU0_PE3_OCP_TXN<9>
  DP7  PE3_TX_DP(7)  OUT  = P3E_CPU0_PE3_OCP_TXP<7>
  DP9  VSS(1213)  GROUND  = GND
  DP11  PE1_RX_DN(9)  IN  = P3E_CPU0_PE1_PCH_RXN<9>
  DP13  PE1_RX_DP(11)  IN  = P3E_CPU0_PE1_PCH_RXP<11>
  DP15  PE3_RX_DP(5)  IN  = P3E_CPU0_PE3_OCP_RXP<5>
  DP17  RSVD(30)  BI  = TP_CPU0_RSVD_30
  DP19  VCCIO(63)  POWER  = PVCCIO_CPU0
  DP21  UPI2_TX_DP(0)  OUT  = TP_CPU0_UPI2_RSVD_CA12
  DP23  DDR3_DQS_DP(16)  BI  = M_D_DQS_DP<16>
  DP25  DDR3_DQ(60)  BI  = M_D_DQ<60>
  DP27  DDR3_DQ(50)  BI  = M_D_DQ<50>
  DP29  DDR3_DQS_DP(15)  BI  = M_D_DQS_DP<15>
  DP31  DDR3_DQ(52)  BI  = M_D_DQ<52>
  DP33  DDR3_DQ(42)  BI  = M_D_DQ<42>
  DP35  DDR3_DQS_DN(14)  BI  = M_D_DQS_DN<14>
  DP37  DDR3_DQ(44)  BI  = M_D_DQ<44>
  DP39  DDR4_DQ(34)  BI  = M_E_DQ<34>
  DP41  DDR4_DQS_DN(13)  BI  = M_E_DQS_DN<13>
  DP45  VSS(1203)  GROUND  = GND
  DP47  VSS(1204)  GROUND  = GND
  DP49  VSS(1205)  GROUND  = GND
  DP51  VSS(1206)  GROUND  = GND
  DP53  VSS(1207)  GROUND  = GND
  DP55  VSS(1208)  GROUND  = GND
  DP57  VSS(1209)  GROUND  = GND
  DP59  VSS(1210)  GROUND  = GND
  DP61  VSS(1211)  GROUND  = GND
  DP63  VSS(1212)  GROUND  = GND
  DP65  RSVD(29)  BI  = TP_CPU0_RSVD_29
  DP67  VSS(132)  GROUND  = GND
  DP69  VSS(131)  GROUND  = GND
  DP71  VSS(130)  GROUND  = GND
  DP73  DDR3_DQ(26)  BI  = M_D_DQ<26>
  DP75  DDR3_DQS_DN(12)  BI  = M_D_DQS_DN<12>
  DP77  DDR3_DQ(28)  BI  = M_D_DQ<28>
  DP79  DDR3_DQS_DP(11)  BI  = M_D_DQS_DP<11>
  DP81  VSS(129)  GROUND  = GND
  DP83  VSS(128)  GROUND  = GND
  DP85  DDR3_DQS_DP(1)  BI  = M_D_DQS_DP<1>
  DR2  VCCIO(65)  POWER  = PVCCIO_CPU0
  DR4  PE1_TX_DP(8)  OUT  = P3E_CPU0_PE1_PCH_TXP<8>
  DR6  VSS(126)  GROUND  = GND
  DR8  PE3_TX_DN(7)  OUT  = P3E_CPU0_PE3_OCP_TXN<7>
  DR10  VCCIO(64)  POWER  = PVCCIO_CPU0
  DR12  PE1_RX_DP(10)  IN  = P3E_CPU0_PE1_PCH_RXP<10>
  DR14  PE3_RX_DN(5)  IN  = P3E_CPU0_PE3_OCP_RXN<5>
  DR16  PE3_RX_DN(4)  IN  = P3E_CPU0_PE3_OCP_RXN<4>
  DR18  PE3_RX_DP(3)  IN  = P3E_CPU0_PE3_OCP_RXP<3>
  DR20  VSS(123)  GROUND  = GND
  DR22  VSS(122)  GROUND  = GND
  DR24  VSS(121)  GROUND  = GND
  DR26  VSS(120)  GROUND  = GND
  DR28  VSS(119)  GROUND  = GND
  DR30  VSS(118)  GROUND  = GND
  DR32  VSS(117)  GROUND  = GND
  DR34  VSS(116)  GROUND  = GND
  DR36  VSS(115)  GROUND  = GND
  DR38  VSS(114)  GROUND  = GND
  DR40  VSS(113)  GROUND  = GND
  DR42  VSS(112)  GROUND  = GND
  DR44  RSVD(28)  BI  = TP_CPU0_RSVD_28
  DR46  DDR4_CS_N(2)  OUT  = M_E_CS_N<2>
  DR48  DDR4_MA(17)  OUT  = M_E_MA<17>
  DR50  DDR4_ODT(0)  OUT  = M_E_ODT<0>
  DR52  DDR4_MA(15)  OUT  = M_E_MA<15>
  DR54  DDR4_CLK_DN(1)  OUT  = M_E_CLK_DN<1>
  DR56  DDR4_CLK_DP(3)  OUT  = M_E_CLK_DP<3>
  DR58  DDR4_MA(3)  OUT  = M_E_MA<3>
  DR60  DDR4_MA(11)  OUT  = M_E_MA<11>
  DR62  DDR4_ACT_N  OUT  = M_E_ACT_N
  DR64  DDR4_CKE(3)  OUT  = M_E_CKE<3>
  DR66  VSS(111)  GROUND  = GND
  DR68  VSS(110)  GROUND  = GND
  DR70  VSS(109)  GROUND  = GND
  DR72  VSS(108)  GROUND  = GND
  DR74  VSS(107)  GROUND  = GND
  DR76  VSS(106)  GROUND  = GND
  DR78  VSS(105)  GROUND  = GND
  DR80  DDR3_DQ(22)  BI  = M_D_DQ<22>
  DR82  DDR3_DQ(19)  BI  = M_D_DQ<19>
  DR84  DDR3_DQ(14)  BI  = M_D_DQ<14>
  DT3  VSS(104)  GROUND  = GND
  DT5  PE1_TX_DN(8)  OUT  = P3E_CPU0_PE1_PCH_TXN<8>
  DT7  PE1_TX_DP(12)  OUT  = P3E_CPU0_PE1_PCH_TXP<12>
  DT9  PE3_TX_DP(6)  OUT  = P3E_CPU0_PE3_OCP_TXP<6>
  DT11  PE1_RX_DN(10)  IN  = P3E_CPU0_PE1_PCH_RXN<10>
  DT13  PE1_RX_DN(11)  IN  = P3E_CPU0_PE1_PCH_RXN<11>
  DT15  PE1_RX_DP(15)  IN  = P3E_CPU0_PE1_PCH_RXP<15>
  DT17  VSS(103)  GROUND  = GND
  DT19  PE3_RX_DN(3)  IN  = P3E_CPU0_PE3_OCP_RXN<3>
  DT21  UPI2_TX_DN(0)  OUT  = TP_CPU0_UPI2_RSVD_CC12
  DT23  DDR3_DQS_DP(7)  BI  = M_D_DQS_DP<7>
  DT25  DDR3_DQ(61)  BI  = M_D_DQ<61>
  DT27  DDR3_DQ(51)  BI  = M_D_DQ<51>
  DT29  DDR3_DQS_DP(6)  BI  = M_D_DQS_DP<6>
  DT31  DDR3_DQ(53)  BI  = M_D_DQ<53>
  DT33  DDR3_DQ(43)  BI  = M_D_DQ<43>
  DT35  DDR3_DQS_DP(5)  BI  = M_D_DQS_DP<5>
  DT37  DDR3_DQ(45)  BI  = M_D_DQ<45>
  DT39  DDR4_DQ(35)  BI  = M_E_DQ<35>
  DT41  DDR4_DQS_DP(4)  BI  = M_E_DQS_DP<4>
  DT45  DDR4_CS_N(6)  OUT  = M_E_CS_N<6>
  DT47  DDR4_CID(2)  OUT  = M_E_C<2>
  DT49  DDR4_ODT(2)  OUT  = M_E_ODT<2>
  DT51  DDR4_MA(13)  OUT  = M_E_MA<13>
  DT53  DDR4_CLK_DP(1)  OUT  = M_E_CLK_DP<1>
  DT55  DDR4_MA(10)  OUT  = M_E_MA<10>
  DT57  DDR4_CLK_DN(3)  OUT  = M_E_CLK_DN<3>
  DT59  DDR4_MA(4)  OUT  = M_E_MA<4>
  DT61  DDR4_ALERT_N  IN  = M_E_ALERT_N
  DT63  DDR3_MA(12)  OUT  = M_D_MA<12>
  DT65  VSS(101)  GROUND  = GND
  DT67  DDR4_DQS_DP(17)  BI  = M_E_DQS_DP<17>
  DT69  VSS(100)  GROUND  = GND
  DT71  RSVD(27)  BI  = TP_CPU0_RSVD_27
  DT73  DDR3_DQ(27)  BI  = M_D_DQ<27>
  DT75  DDR3_DQS_DP(3)  BI  = M_D_DQS_DP<3>
  DT77  DDR3_DQ(29)  BI  = M_D_DQ<29>
  DT79  VSS(99)  GROUND  = GND
  DT81  DDR3_DQ(18)  BI  = M_D_DQ<18>
  DT83  VSS(98)  GROUND  = GND
  DT85  VSS(97)  GROUND  = GND
  DU2  PE1_TX_DP(9)  OUT  = P3E_CPU0_PE1_PCH_TXP<9>
  DU4  PE1_TX_DP(10)  OUT  = P3E_CPU0_PE1_PCH_TXP<10>
  DU6  PE1_TX_DN(11)  OUT  = P3E_CPU0_PE1_PCH_TXN<11>
  DU8  PE3_TX_DN(6)  OUT  = P3E_CPU0_PE3_OCP_TXN<6>
  DU10  VSS(96)  GROUND  = GND
  DU12  PE1_RX_DP(12)  IN  = P3E_CPU0_PE1_PCH_RXP<12>
  DU14  VSS(95)  GROUND  = GND
  DU16  PE1_RX_DN(15)  IN  = P3E_CPU0_PE1_PCH_RXN<15>
  DU18  PE3_RX_DP(1)  IN  = P3E_CPU0_PE3_OCP_RXP<1>
  DU20  VCCIO(66)  POWER  = PVCCIO_CPU0
  DU22  VSS(93)  GROUND  = GND
  DU24  DDR3_DQ(57)  BI  = M_D_DQ<57>
  DU26  VSS(92)  GROUND  = GND
  DU28  DDR3_DQ(55)  BI  = M_D_DQ<55>
  DU30  DDR3_DQ(49)  BI  = M_D_DQ<49>
  DU32  VSS(91)  GROUND  = GND
  DU34  DDR3_DQ(47)  BI  = M_D_DQ<47>
  DU36  DDR3_DQ(41)  BI  = M_D_DQ<41>
  DU38  VSS(90)  GROUND  = GND
  DU40  DDR4_DQ(39)  BI  = M_E_DQ<39>
  DU42  DDR4_DQ(32)  BI  = M_E_DQ<32>
  DU44  RSVD(26)  BI  = TP_CPU0_RSVD_26
  DU46  VCCD345(21)  POWER  = PVDDQ_DEF
  DU48  VCCD345(20)  POWER  = PVDDQ_DEF
  DU50  VCCD345(19)  POWER  = PVDDQ_DEF
  DU52  VCCD345(18)  POWER  = PVDDQ_DEF
  DU54  VCCD345(17)  POWER  = PVDDQ_DEF
  DU56  VCCD345(16)  POWER  = PVDDQ_DEF
  DU58  VCCD345(15)  POWER  = PVDDQ_DEF
  DU60  VCCD345(14)  POWER  = PVDDQ_DEF
  DU62  VCCD345(13)  POWER  = PVDDQ_DEF
  DU64  VCCD345(12)  POWER  = PVDDQ_DEF
  DU66  DDR4_ECC(6)  BI  = M_E_ECC<6>
  DU68  DDR4_ECC(4)  BI  = M_E_ECC<4>
  DU70  VSS(89)  GROUND  = GND
  DU72  VSS(88)  GROUND  = GND
  DU74  DDR3_DQ(31)  BI  = M_D_DQ<31>
  DU76  DDR3_DQ(25)  BI  = M_D_DQ<25>
  DU78  VSS(87)  GROUND  = GND
  DU80  VSS(86)  GROUND  = GND
  DU82  VSS(85)  GROUND  = GND
  DU84  VSS(84)  GROUND  = GND
  DV3  PE1_TX_DN(9)  OUT  = P3E_CPU0_PE1_PCH_TXN<9>
  DV5  PE1_TX_DP(11)  OUT  = P3E_CPU0_PE1_PCH_TXP<11>
  DV7  PE1_TX_DN(12)  OUT  = P3E_CPU0_PE1_PCH_TXN<12>
  DV9  PE3_TX_DP(5)  OUT  = P3E_CPU0_PE3_OCP_TXP<5>
  DV11  VCCIO(3)  POWER  = PVCCIO_CPU0
  DV13  PE1_RX_DN(12)  IN  = P3E_CPU0_PE1_PCH_RXN<12>
  DV15  PE1_RX_DP(14)  IN  = P3E_CPU0_PE1_PCH_RXP<14>
  DV17  PE3_RX_DP(2)  IN  = P3E_CPU0_PE3_OCP_RXP<2>
  DV19  VSS(1214)  GROUND  = GND
  DV21  VSS(83)  GROUND  = GND
  DV23  DDR3_DQS_DN(7)  BI  = M_D_DQS_DN<7>
  DV25  VSS(82)  GROUND  = GND
  DV27  VSS(81)  GROUND  = GND
  DV29  DDR3_DQS_DN(6)  BI  = M_D_DQS_DN<6>
  DV31  VSS(80)  GROUND  = GND
  DV33  VSS(79)  GROUND  = GND
  DV35  DDR3_DQS_DN(5)  BI  = M_D_DQS_DN<5>
  DV37  VSS(78)  GROUND  = GND
  DV39  VSS(77)  GROUND  = GND
  DV41  DDR4_DQS_DN(4)  BI  = M_E_DQS_DN<4>
  DV45  DDR3_CS_N(6)  OUT  = M_D_CS_N<6>
  DV47  DDR3_CID(2)  OUT  = M_D_C<2>
  DV49  DDR3_MA(15)  OUT  = M_D_MA<15>
  DV51  DDR4_CS_N(0)  OUT  = M_E_CS_N<0>
  DV53  DDR4_PAR  OUT  = M_E_PAR
  DV55  DDR4_BA(1)  OUT  = M_E_BA<1>
  DV57  DDR4_MA(2)  OUT  = M_E_MA<2>
  DV59  DDR4_MA(9)  OUT  = M_E_MA<9>
  DV61  RSVD(25)  BI  = TP_CPU0_RSVD_25
  DV63  DDR345_RESET_N  OUT  = M_DEF_RST_N
  DV65  DDR4_ECC(2)  BI  = M_E_ECC<2>
  DV67  DDR4_DQS_DN(17)  BI  = M_E_DQS_DN<17>
  DV69  DDR4_ECC(5)  BI  = M_E_ECC<5>
  DV71  RSVD(24)  BI  = TP_CPU0_RSVD_24
  DV73  VSS(76)  GROUND  = GND
  DV75  DDR3_DQS_DN(3)  BI  = M_D_DQS_DN<3>
  DV77  VSS(75)  GROUND  = GND
  DV79  DDR4_DQS_DP(11)  BI  = M_E_DQS_DP<11>
  DV81  VSS(74)  GROUND  = GND
  DV83  DDR3_DQ(10)  BI  = M_D_DQ<10>
  DV85  DDR3_DQ(15)  BI  = M_D_DQ<15>
  DW2  VSS(1239)  GROUND  = GND
  DW4  PE1_TX_DN(10)  OUT  = P3E_CPU0_PE1_PCH_TXN<10>
  DW6  PE1_TX_DP(13)  OUT  = P3E_CPU0_PE1_PCH_TXP<13>
  DW8  VSS(58)  GROUND  = GND
  DW10  PE3_TX_DN(5)  OUT  = P3E_CPU0_PE3_OCP_TXN<5>
  DW12  VSS(73)  GROUND  = GND
  DW14  PE1_RX_DN(13)  IN  = P3E_CPU0_PE1_PCH_RXN<13>
  DW16  PE3_RX_DN(2)  IN  = P3E_CPU0_PE3_OCP_RXN<2>
  DW18  PE3_RX_DN(1)  IN  = P3E_CPU0_PE3_OCP_RXN<1>
  DW20  VSS(72)  GROUND  = GND
  DW22  DDR3_DQ(63)  BI  = M_D_DQ<63>
  DW24  VSS(71)  GROUND  = GND
  DW26  DDR4_DQS_DP(15)  BI  = M_E_DQS_DP<15>
  DW28  VSS(70)  GROUND  = GND
  DW30  VSS(69)  GROUND  = GND
  DW32  DDR4_DQS_DP(14)  BI  = M_E_DQS_DP<14>
  DW34  VSS(68)  GROUND  = GND
  DW36  VSS(67)  GROUND  = GND
  DW38  DDR3_DQS_DP(13)  BI  = M_D_DQS_DP<13>
  DW40  VSS(66)  GROUND  = GND
  DW42  DDR4_DQ(33)  BI  = M_E_DQ<33>
  DW44  RSVD(23)  BI  = TP_CPU0_RSVD_23
